# TIMECARD (Time Appliance Project (Time Card)) — schematic netlist excerpt (pin names and nets, part order shuffled) for the footprints in the layout excerpt that follows; sources: Cadence DE-HDL packaged netlist, KiCad conversion of R4006-B0001-02_R01.brd

R264  RESISTOR  100KOHM 1%  pkg SMC_0402R_H016  page 21 : \1\ = XP3R3V_FPGA ; \2\ = R_MAC_UART_RX_FPGA_TX
R163  RESISTOR  4.7KOHM 1%  pkg SMC_0402R_H016  page 16 : \1\ = UNNAMED_5_24LC16BTISTTSSOP8_I_2 ; \2\ = SG

(kicad_pcb
	(version 20260206)
	(generator "pcbnew")
	(generator_version "10.0")
	(general
		(thickness 1.6)
		(legacy_teardrops no)
	)
	(paper "A4")
	(title_block
		(title "timecard-production-celestica-r4006 — R4006-B0001-02_R01.brd")
		(comment 1 "Time Appliance Project (Time Card) / footprints 871-872 of 1113")
	)
	(layers
		(0 "F.Cu" signal "TOP")
		(4 "In1.Cu" signal "L02_GND1")
		(6 "In2.Cu" signal "L03_SIG1")
		(8 "In3.Cu" signal "L04_GND2")
		(10 "In4.Cu" signal "L05_VCC1")
		(12 "In5.Cu" signal "L06_VCC2")
		(14 "In6.Cu" signal "L07_GND3")
		(16 "In7.Cu" signal "L08_SIG2")
		(18 "In8.Cu" signal "L09_GND4")
		(2 "B.Cu" signal "BOTTOM")
		(9 "F.Adhes" user "F.Adhesive")
		(11 "B.Adhes" user "B.Adhesive")
		(13 "F.Paste" user "Package Geometry/Pastemask Top")
		(15 "B.Paste" user "Package Geometry/Pastemask Bottom")
		(5 "F.SilkS" user "Ref Des/Silkscreen Top")
		(7 "B.SilkS" user "Ref Des/Silkscreen Bottom")
		(1 "F.Mask" user "Board Geometry/Soldermask Top")
		(3 "B.Mask" user "Board Geometry/Soldermask Bottom")
		(17 "Dwgs.User" user "User.Drawings")
		(19 "Cmts.User" user "User.Comments")
		(21 "Eco1.User" user "User.Eco1")
		(23 "Eco2.User" user "User.Eco2")
		(25 "Edge.Cuts" user "Board Geometry/Outline")
		(27 "Margin" user)
		(31 "F.CrtYd" user "Package Geometry/Place Bound Top")
		(29 "B.CrtYd" user "Package Geometry/Place Bound Bottom")
		(35 "F.Fab" user "Ref Des/Assembly Top")
		(33 "B.Fab" user "Ref Des/Assembly Bottom")
	)
	(footprint ""
		(layer "B.Cu")
		(at 124.587 -51.435 180)
		(property "Reference" "R264"
			(at -3.302 -0.16637 0)
			(unlocked yes)
			(layer "B.SilkS")
			(effects
				(font
					(size 0.7874 0.5842)
					(thickness 0.1524)
				)
				(justify mirror)
			)
		)
		(property "Value" "VAL*"
			(at -0.02032 2.13233 180)
			(unlocked yes)
			(layer "B.Fab")
			(hide yes)
			(effects
				(font
					(size 0.7874 0.5842)
					(thickness 0.1524)
				)
				(justify mirror)
			)
		)
		(property "Tolerance" "TOL*"
			(at -0.044704 3.05435 180)
			(unlocked yes)
			(layer "Cmts.User")
			(hide yes)
			(effects
				(font
					(size 0.7874 0.5842)
					(thickness 0.1524)
				)
				(justify mirror)
			)
		)
		(property "User Part Number" "PARTNUM*"
			(at -0.02032 4.024884 180)
			(unlocked yes)
			(layer "Cmts.User")
			(hide yes)
			(effects
				(font
					(size 0.7874 0.5842)
					(thickness 0.1524)
				)
				(justify mirror)
			)
		)
		(property "Device Type" "RESISTOR-G155-11003-01,100KOHMA"
			(at -0.008382 1.210564 180)
			(unlocked yes)
			(layer "B.Fab")
			(hide yes)
			(effects
				(font
					(size 0.7874 0.5842)
					(thickness 0.1524)
				)
				(justify mirror)
			)
		)
		(duplicate_pad_numbers_are_jumpers no)
		(fp_line
			(start 1.143 0.5588)
			(end -1.143 0.5588)
			(stroke
				(width 0.1)
				(type default)
			)
			(layer "B.SilkS")
		)
		(fp_line
			(start 1.143 -0.5588)
			(end 1.143 0.5588)
			(stroke
				(width 0.1)
				(type default)
			)
			(layer "B.SilkS")
		)
		(fp_line
			(start -1.143 0.5588)
			(end -1.143 -0.5588)
			(stroke
				(width 0.1)
				(type default)
			)
			(layer "B.SilkS")
		)
		(fp_line
			(start -1.143 -0.5588)
			(end 1.143 -0.5588)
			(stroke
				(width 0.1)
				(type default)
			)
			(layer "B.SilkS")
		)
		(fp_rect
			(start 1.143 0.5588)
			(end -1.143 -0.5588)
			(stroke
				(width 0)
				(type default)
			)
			(fill no)
			(layer "B.CrtYd")
		)
		(fp_line
			(start 0.508 0.3048)
			(end -0.508 0.3048)
			(stroke
				(width 0.1)
				(type default)
			)
			(layer "B.Fab")
		)
		(fp_line
			(start 0.508 -0.3048)
			(end 0.508 0.3048)
			(stroke
				(width 0.1)
				(type default)
			)
			(layer "B.Fab")
		)
		(fp_line
			(start -0.508 0.3048)
			(end -0.508 -0.3048)
			(stroke
				(width 0.1)
				(type default)
			)
			(layer "B.Fab")
		)
		(fp_line
			(start -0.508 -0.3048)
			(end 0.508 -0.3048)
			(stroke
				(width 0.1)
				(type default)
			)
			(layer "B.Fab")
		)
		(pad "1" smd rect
			(at 0.5334 0)
			(size 0.7112 0.6096)
			(layers "B.Cu" "B.Mask" "B.Paste")
			(net "XP3R3V_FPGA")
		)
		(pad "2" smd rect
			(at -0.5334 0)
			(size 0.7112 0.6096)
			(layers "B.Cu" "B.Mask" "B.Paste")
			(net "R_MAC_UART_RX_FPGA_TX")
		)
		(zone
			(layer "B.Cu")
			(hatch none 0.5)
			(connect_pads
				(clearance 0)
			)
			(min_thickness 0.25)
			(keepout
				(tracks not_allowed)
				(vias allowed)
				(pads allowed)
				(copperpour not_allowed)
				(footprints allowed)
			)
			(placement
				(enabled no)
				(sheetname "")
			)
			(fill
				(thermal_gap 0.5)
				(thermal_bridge_width 0.5)
				(island_removal_mode 0)
			)
			(polygon
				(pts
					(xy 124.5108 -51.7398) (xy 124.5108 -51.1302) (xy 124.6632 -51.1302) (xy 124.6632 -51.7398)
				)
			)
		)
		(zone
			(layer "B.Cu")
			(hatch none 0.5)
			(connect_pads
				(clearance 0)
			)
			(min_thickness 0.25)
			(keepout
				(tracks allowed)
				(vias not_allowed)
				(pads allowed)
				(copperpour not_allowed)
				(footprints allowed)
			)
			(placement
				(enabled no)
				(sheetname "")
			)
			(fill
				(thermal_gap 0.5)
				(thermal_bridge_width 0.5)
				(island_removal_mode 0)
			)
			(polygon
				(pts
					(xy 124.5108 -51.7398) (xy 124.5108 -51.1302) (xy 124.6632 -51.1302) (xy 124.6632 -51.7398)
				)
			)
		)
	)
	(footprint ""
		(layer "B.Cu")
		(at 17.7292 -23.6728 90)
		(property "Reference" "R163"
			(at 1.3462 -1.13157 270)
			(unlocked yes)
			(layer "B.SilkS")
			(effects
				(font
					(size 0.7874 0.5842)
					(thickness 0.1524)
				)
				(justify mirror)
			)
		)
		(property "Value" "VAL*"
			(at -0.02032 2.13233 90)
			(unlocked yes)
			(layer "B.Fab")
			(hide yes)
			(effects
				(font
					(size 0.7874 0.5842)
					(thickness 0.1524)
				)
				(justify mirror)
			)
		)
		(property "Tolerance" "TOL*"
			(at -0.044704 3.05435 90)
			(unlocked yes)
			(layer "Cmts.User")
			(hide yes)
			(effects
				(font
					(size 0.7874 0.5842)
					(thickness 0.1524)
				)
				(justify mirror)
			)
		)
		(property "User Part Number" "PARTNUM*"
			(at -0.02032 4.024884 90)
			(unlocked yes)
			(layer "Cmts.User")
			(hide yes)
			(effects
				(font
					(size 0.7874 0.5842)
					(thickness 0.1524)
				)
				(justify mirror)
			)
		)
		(property "Device Type" "RESISTOR-G155-14701-01,4.7KOHMA"
			(at -0.008382 1.210564 90)
			(unlocked yes)
			(layer "B.Fab")
			(hide yes)
			(effects
				(font
					(size 0.7874 0.5842)
					(thickness 0.1524)
				)
				(justify mirror)
			)
		)
		(duplicate_pad_numbers_are_jumpers no)
		(fp_line
			(start 1.143 -0.5588)
			(end 1.143 0.5588)
			(stroke
				(width 0.1)
				(type default)
			)
			(layer "B.SilkS")
		)
		(fp_line
			(start -1.143 -0.5588)
			(end 1.143 -0.5588)
			(stroke
				(width 0.1)
				(type default)
			)
			(layer "B.SilkS")
		)
		(fp_line
			(start 1.143 0.5588)
			(end -1.143 0.5588)
			(stroke
				(width 0.1)
				(type default)
			)
			(layer "B.SilkS")
		)
		(fp_line
			(start -1.143 0.5588)
			(end -1.143 -0.5588)
			(stroke
				(width 0.1)
				(type default)
			)
			(layer "B.SilkS")
		)
		(fp_poly
			(pts
				(xy 1.143 0.5588) (xy -1.143 0.5588) (xy -1.143 -0.5588) (xy 1.143 -0.5588)
			)
			(stroke
				(width 0)
				(type default)
			)
			(fill no)
			(layer "B.CrtYd")
		)
		(fp_line
			(start 0.508 -0.3048)
			(end 0.508 0.3048)
			(stroke
				(width 0.1)
				(type default)
			)
			(layer "B.Fab")
		)
		(fp_line
			(start -0.508 -0.3048)
			(end 0.508 -0.3048)
			(stroke
				(width 0.1)
				(type default)
			)
			(layer "B.Fab")
		)
		(fp_line
			(start 0.508 0.3048)
			(end -0.508 0.3048)
			(stroke
				(width 0.1)
				(type default)
			)
			(layer "B.Fab")
		)
		(fp_line
			(start -0.508 0.3048)
			(end -0.508 -0.3048)
			(stroke
				(width 0.1)
				(type default)
			)
			(layer "B.Fab")
		)
		(pad "1" smd rect
			(at 0.5334 0 270)
			(size 0.7112 0.6096)
			(layers "B.Cu" "B.Mask" "B.Paste")
			(net "UNNAMED_5_24LC16BTISTTSSOP8_I_2")
		)
		(pad "2" smd rect
			(at -0.5334 0 270)
			(size 0.7112 0.6096)
			(layers "B.Cu" "B.Mask" "B.Paste")
			(net "SG")
		)
		(zone
			(layer "B.Cu")
			(hatch none 0.5)
			(connect_pads
				(clearance 0)
			)
			(min_thickness 0.25)
			(keepout
				(tracks allowed)
				(vias not_allowed)
				(pads allowed)
				(copperpour not_allowed)
				(footprints allowed)
			)
			(placement
				(enabled no)
				(sheetname "")
			)
			(fill
				(thermal_gap 0.5)
				(thermal_bridge_width 0.5)
				(island_removal_mode 0)
			)
			(polygon
				(pts
					(xy 18.034 -23.749) (xy 17.4244 -23.749) (xy 17.4244 -23.5966) (xy 18.034 -23.5966)
				)
			)
		)
		(zone
			(layer "B.Cu")
			(hatch none 0.5)
			(connect_pads
				(clearance 0)
			)
			(min_thickness 0.25)
			(keepout
				(tracks not_allowed)
				(vias allowed)
				(pads allowed)
				(copperpour not_allowed)
				(footprints allowed)
			)
			(placement
				(enabled no)
				(sheetname "")
			)
			(fill
				(thermal_gap 0.5)
				(thermal_bridge_width 0.5)
				(island_removal_mode 0)
			)
			(polygon
				(pts
					(xy 18.034 -23.749) (xy 17.4244 -23.749) (xy 17.4244 -23.5966) (xy 18.034 -23.5966)
				)
			)
		)
	)
)
